(kicad_pcb
	(version 20260206)
	(generator "pcbnew")
	(generator_version "10.0")
	(general
		(thickness 1.6)
		(legacy_teardrops no)
	)
	(paper "A4")
	(title_block
		(title "baseboard — 13948-1b.1110WZS1818.brd")
		(comment 1 "Honey Badger (Wiwynn) / footprints 1225-1232 of 2523")
	)
	(layers
		(0 "F.Cu" signal "TOP")
		(4 "In1.Cu" signal "L2GND")
		(6 "In2.Cu" signal "L3")
		(8 "In3.Cu" signal "L4VCC")
		(10 "In4.Cu" signal "L5VCC")
		(12 "In5.Cu" signal "L6")
		(14 "In6.Cu" signal "L7GND")
		(2 "B.Cu" signal "BOTTOM")
		(9 "F.Adhes" user "F.Adhesive")
		(11 "B.Adhes" user "B.Adhesive")
		(13 "F.Paste" user "Package Geometry/Pastemask Top")
		(15 "B.Paste" user "Package Geometry/Pastemask Bottom")
		(5 "F.SilkS" user "Ref Des/Silkscreen Top")
		(7 "B.SilkS" user "Ref Des/Silkscreen Bottom")
		(1 "F.Mask" user "Board Geometry/Soldermask Top")
		(3 "B.Mask" user "Board Geometry/Soldermask Bottom")
		(17 "Dwgs.User" user "User.Drawings")
		(19 "Cmts.User" user "User.Comments")
		(21 "Eco1.User" user "User.Eco1")
		(23 "Eco2.User" user "User.Eco2")
		(25 "Edge.Cuts" user "Board Geometry/Outline")
		(27 "Margin" user)
		(31 "F.CrtYd" user "Package Geometry/Place Bound Top")
		(29 "B.CrtYd" user "Package Geometry/Place Bound Bottom")
		(35 "F.Fab" user "Ref Des/Assembly Top")
		(33 "B.Fab" user "Ref Des/Assembly Bottom")
	)
	(footprint ""
		(layer "F.Cu")
		(at 327.383648 -110.416848 90)
		(property "Reference" "PC28"
			(at 0 0 90)
			(layer "F.SilkS")
			(hide yes)
			(effects
				(font
					(size 1.27 1.27)
				)
			)
		)
		(property "Value" "SC2K2P50V3KX-GP"
			(at 0 -2.8194 90)
			(unlocked yes)
			(layer "F.Fab")
			(hide yes)
			(effects
				(font
					(size 1.016 1.016)
					(thickness 0.1524)
				)
			)
		)
		(property "Device Type" "C603"
			(at 0 -4.3434 90)
			(unlocked yes)
			(layer "F.Fab")
			(hide yes)
			(effects
				(font
					(size 1.016 1.016)
					(thickness 0.1524)
				)
			)
		)
		(duplicate_pad_numbers_are_jumpers no)
		(fp_line
			(start 0.508 0)
			(end -0.508 0)
			(stroke
				(width 0.2032)
				(type default)
			)
			(layer "F.SilkS")
		)
		(fp_rect
			(start -0.5842 1.3335)
			(end 0.5842 -1.3335)
			(stroke
				(width 0)
				(type default)
			)
			(fill no)
			(layer "F.CrtYd")
		)
		(fp_rect
			(start -0.5842 1.3335)
			(end 0.5842 -1.3335)
			(stroke
				(width 0)
				(type default)
			)
			(fill no)
			(layer "F.Fab")
		)
		(pad "1" smd custom
			(at 0 -0.762 90)
			(size 0.2159 0.2159)
			(layers "F.Cu" "F.Mask" "F.Paste")
			(net "P3V3_STBY_LL")
			(options
				(clearance outline)
				(anchor circle)
			)
			(primitives
				(gr_poly
					(pts
						(arc
							(start -0.3302 -0.4318)
							(mid -0.402042 -0.402042)
							(end -0.4318 -0.3302)
						)
						(arc
							(start -0.4318 0.3302)
							(mid -0.402042 0.402042)
							(end -0.3302 0.4318)
						)
						(arc
							(start 0.3302 0.4318)
							(mid 0.402042 0.402042)
							(end 0.4318 0.3302)
						)
						(arc
							(start 0.4318 -0.3302)
							(mid 0.402042 -0.402042)
							(end 0.3302 -0.4318)
						)
					)
					(width 0)
					(fill yes)
				)
			)
		)
		(pad "2" smd custom
			(at 0 0.762 90)
			(size 0.2159 0.2159)
			(layers "F.Cu" "F.Mask" "F.Paste")
			(net "P3V3_STBY_SNB")
			(options
				(clearance outline)
				(anchor circle)
			)
			(primitives
				(gr_poly
					(pts
						(arc
							(start -0.3302 -0.4318)
							(mid -0.402042 -0.402042)
							(end -0.4318 -0.3302)
						)
						(arc
							(start -0.4318 0.3302)
							(mid -0.402042 0.402042)
							(end -0.3302 0.4318)
						)
						(arc
							(start 0.3302 0.4318)
							(mid 0.402042 0.402042)
							(end 0.4318 0.3302)
						)
						(arc
							(start 0.4318 -0.3302)
							(mid 0.402042 -0.402042)
							(end 0.3302 -0.4318)
						)
					)
					(width 0)
					(fill yes)
				)
			)
		)
	)
	(footprint ""
		(layer "F.Cu")
		(at 92.21597 -94.234 -90)
		(property "Reference" "SR781"
			(at 0 0 270)
			(layer "F.SilkS")
			(hide yes)
			(effects
				(font
					(size 1.27 1.27)
				)
			)
		)
		(property "Value" "4K7R2F-GP"
			(at 0.064008 -3.993896 270)
			(unlocked yes)
			(layer "F.Fab")
			(hide yes)
			(effects
				(font
					(size 1.016 1.016)
					(thickness 0.1524)
				)
			)
		)
		(property "Device Type" "R402H16"
			(at 0.064008 -5.517896 270)
			(unlocked yes)
			(layer "F.Fab")
			(hide yes)
			(effects
				(font
					(size 1.016 1.016)
					(thickness 0.1524)
				)
			)
		)
		(duplicate_pad_numbers_are_jumpers no)
		(fp_line
			(start -0.508 -0.9398)
			(end -0.508 0.9398)
			(stroke
				(width 0.1524)
				(type default)
			)
			(layer "F.SilkS")
		)
		(fp_line
			(start 0.508 -0.9398)
			(end -0.508 -0.9398)
			(stroke
				(width 0.1524)
				(type default)
			)
			(layer "F.SilkS")
		)
		(fp_rect
			(start -0.508 0.9398)
			(end 0.508 -0.9398)
			(stroke
				(width 0)
				(type default)
			)
			(fill no)
			(layer "F.CrtYd")
		)
		(fp_rect
			(start -0.508 0.9398)
			(end 0.508 -0.9398)
			(stroke
				(width 0)
				(type default)
			)
			(fill no)
			(layer "F.Fab")
		)
		(pad "1" smd custom
			(at 0 -0.4445 270)
			(size 0.1397 0.1397)
			(layers "F.Cu" "F.Mask" "F.Paste")
			(net "EXP_XM_ADDR_23")
			(options
				(clearance outline)
				(anchor circle)
			)
			(primitives
				(gr_poly
					(pts
						(arc
							(start -0.1778 -0.2794)
							(mid -0.249642 -0.249642)
							(end -0.2794 -0.1778)
						)
						(arc
							(start -0.2794 0.1778)
							(mid -0.249642 0.249642)
							(end -0.1778 0.2794)
						)
						(arc
							(start 0.1778 0.2794)
							(mid 0.249642 0.249642)
							(end 0.2794 0.1778)
						)
						(arc
							(start 0.2794 -0.1778)
							(mid 0.249642 -0.249642)
							(end 0.1778 -0.2794)
						)
					)
					(width 0)
					(fill yes)
				)
			)
		)
		(pad "2" smd custom
			(at 0 0.4445 270)
			(size 0.1397 0.1397)
			(layers "F.Cu" "F.Mask" "F.Paste")
			(net "GND")
			(options
				(clearance outline)
				(anchor circle)
			)
			(primitives
				(gr_poly
					(pts
						(arc
							(start -0.1778 -0.2794)
							(mid -0.249642 -0.249642)
							(end -0.2794 -0.1778)
						)
						(arc
							(start -0.2794 0.1778)
							(mid -0.249642 0.249642)
							(end -0.1778 0.2794)
						)
						(arc
							(start 0.1778 0.2794)
							(mid 0.249642 0.249642)
							(end 0.2794 0.1778)
						)
						(arc
							(start 0.2794 -0.1778)
							(mid 0.249642 -0.249642)
							(end 0.1778 -0.2794)
						)
					)
					(width 0)
					(fill yes)
				)
			)
		)
	)
	(footprint ""
		(layer "F.Cu")
		(at 318.516 -176.276)
		(property "Reference" "C189"
			(at 0 0 0)
			(layer "F.SilkS")
			(hide yes)
			(effects
				(font
					(size 1.27 1.27)
				)
			)
		)
		(property "Value" "SCD1U16V2KX-3GP"
			(at 1.1811 -2.7051 0)
			(unlocked yes)
			(layer "F.Fab")
			(hide yes)
			(effects
				(font
					(size 1.016 1.016)
					(thickness 0.1524)
				)
			)
		)
		(property "Device Type" "C402H22"
			(at 1.1811 -4.2291 0)
			(unlocked yes)
			(layer "F.Fab")
			(hide yes)
			(effects
				(font
					(size 1.016 1.016)
					(thickness 0.1524)
				)
			)
		)
		(duplicate_pad_numbers_are_jumpers no)
		(fp_rect
			(start -0.4318 0.9525)
			(end 0.4318 -0.9525)
			(stroke
				(width 0)
				(type default)
			)
			(fill no)
			(layer "F.CrtYd")
		)
		(fp_rect
			(start -0.4318 0.9525)
			(end 0.4318 -0.9525)
			(stroke
				(width 0)
				(type default)
			)
			(fill no)
			(layer "F.Fab")
		)
		(pad "1" smd custom
			(at 0 -0.4445)
			(size 0.1524 0.1524)
			(layers "F.Cu" "F.Mask" "F.Paste")
			(net "ADCAV33")
			(options
				(clearance outline)
				(anchor circle)
			)
			(primitives
				(gr_poly
					(pts
						(arc
							(start 0.3048 -0.2032)
							(mid 0.275042 -0.275042)
							(end 0.2032 -0.3048)
						)
						(arc
							(start -0.2032 -0.3048)
							(mid -0.275042 -0.275042)
							(end -0.3048 -0.2032)
						)
						(arc
							(start -0.3048 0.2032)
							(mid -0.275042 0.275042)
							(end -0.2032 0.3048)
						)
						(arc
							(start 0.2032 0.3048)
							(mid 0.275042 0.275042)
							(end 0.3048 0.2032)
						)
					)
					(width 0)
					(fill yes)
				)
			)
		)
		(pad "2" smd custom
			(at 0 0.4445)
			(size 0.1524 0.1524)
			(layers "F.Cu" "F.Mask" "F.Paste")
			(net "ADCVREFFP")
			(options
				(clearance outline)
				(anchor circle)
			)
			(primitives
				(gr_poly
					(pts
						(arc
							(start 0.3048 -0.2032)
							(mid 0.275042 -0.275042)
							(end 0.2032 -0.3048)
						)
						(arc
							(start -0.2032 -0.3048)
							(mid -0.275042 -0.275042)
							(end -0.3048 -0.2032)
						)
						(arc
							(start -0.3048 0.2032)
							(mid -0.275042 0.275042)
							(end -0.2032 0.3048)
						)
						(arc
							(start 0.2032 0.3048)
							(mid 0.275042 0.275042)
							(end 0.3048 0.2032)
						)
					)
					(width 0)
					(fill yes)
				)
			)
		)
	)
	(footprint ""
		(layer "F.Cu")
		(at 89.29497 -112.014 180)
		(property "Reference" "SC1238"
			(at 0 0 180)
			(layer "F.SilkS")
			(hide yes)
			(effects
				(font
					(size 1.27 1.27)
				)
			)
		)
		(property "Value" "SCD1U6D3V1KX-GP"
			(at -2.8321 -1.7399 180)
			(unlocked yes)
			(layer "F.Fab")
			(hide yes)
			(effects
				(font
					(size 1.016 1.016)
					(thickness 0.1524)
				)
			)
		)
		(property "Device Type" "C0201H13"
			(at -2.8321 -3.2639 180)
			(unlocked yes)
			(layer "F.Fab")
			(hide yes)
			(effects
				(font
					(size 1.016 1.016)
					(thickness 0.1524)
				)
			)
		)
		(duplicate_pad_numbers_are_jumpers no)
		(fp_rect
			(start -0.2794 0.6477)
			(end 0.2794 -0.6477)
			(stroke
				(width 0)
				(type default)
			)
			(fill no)
			(layer "F.CrtYd")
		)
		(fp_rect
			(start -0.2794 0.6477)
			(end 0.2794 -0.6477)
			(stroke
				(width 0)
				(type default)
			)
			(fill no)
			(layer "F.Fab")
		)
		(pad "1" smd custom
			(at 0 -0.2794 180)
			(size 0.0762 0.0762)
			(layers "F.Cu" "F.Mask" "F.Paste")
			(net "P1V8_E")
			(options
				(clearance outline)
				(anchor circle)
			)
			(primitives
				(gr_poly
					(pts
						(arc
							(start 0.1524 -0.127)
							(mid 0.137521 -0.162921)
							(end 0.1016 -0.1778)
						)
						(arc
							(start -0.1016 -0.1778)
							(mid -0.137521 -0.162921)
							(end -0.1524 -0.127)
						)
						(arc
							(start -0.1524 0.127)
							(mid -0.137521 0.162921)
							(end -0.1016 0.1778)
						)
						(arc
							(start 0.1016 0.1778)
							(mid 0.137521 0.162921)
							(end 0.1524 0.127)
						)
					)
					(width 0)
					(fill yes)
				)
			)
		)
		(pad "2" smd custom
			(at 0 0.2794 180)
			(size 0.0762 0.0762)
			(layers "F.Cu" "F.Mask" "F.Paste")
			(net "GND")
			(options
				(clearance outline)
				(anchor circle)
			)
			(primitives
				(gr_poly
					(pts
						(arc
							(start 0.1524 -0.127)
							(mid 0.137521 -0.162921)
							(end 0.1016 -0.1778)
						)
						(arc
							(start -0.1016 -0.1778)
							(mid -0.137521 -0.162921)
							(end -0.1524 -0.127)
						)
						(arc
							(start -0.1524 0.127)
							(mid -0.137521 0.162921)
							(end -0.1016 0.1778)
						)
						(arc
							(start 0.1016 0.1778)
							(mid 0.137521 0.162921)
							(end 0.1524 0.127)
						)
					)
					(width 0)
					(fill yes)
				)
			)
		)
	)
	(footprint ""
		(layer "F.Cu")
		(at 326.263 -80.391)
		(property "Reference" "R486"
			(at 0 0 0)
			(layer "F.SilkS")
			(hide yes)
			(effects
				(font
					(size 1.27 1.27)
				)
			)
		)
		(property "Value" "2K2R2J-2-GP"
			(at 0.064008 -3.993896 0)
			(unlocked yes)
			(layer "F.Fab")
			(hide yes)
			(effects
				(font
					(size 1.016 1.016)
					(thickness 0.1524)
				)
			)
		)
		(property "Device Type" "R402H16"
			(at 0.064008 -5.517896 0)
			(unlocked yes)
			(layer "F.Fab")
			(hide yes)
			(effects
				(font
					(size 1.016 1.016)
					(thickness 0.1524)
				)
			)
		)
		(duplicate_pad_numbers_are_jumpers no)
		(fp_line
			(start -0.508 -0.9398)
			(end -0.508 0.9398)
			(stroke
				(width 0.1524)
				(type default)
			)
			(layer "F.SilkS")
		)
		(fp_line
			(start 0.508 -0.9398)
			(end -0.508 -0.9398)
			(stroke
				(width 0.1524)
				(type default)
			)
			(layer "F.SilkS")
		)
		(fp_rect
			(start -0.508 0.9398)
			(end 0.508 -0.9398)
			(stroke
				(width 0)
				(type default)
			)
			(fill no)
			(layer "F.CrtYd")
		)
		(fp_rect
			(start -0.508 0.9398)
			(end 0.508 -0.9398)
			(stroke
				(width 0)
				(type default)
			)
			(fill no)
			(layer "F.Fab")
		)
		(pad "1" smd custom
			(at 0 -0.4445)
			(size 0.1397 0.1397)
			(layers "F.Cu" "F.Mask" "F.Paste")
			(net "P3V3_STBY")
			(options
				(clearance outline)
				(anchor circle)
			)
			(primitives
				(gr_poly
					(pts
						(arc
							(start -0.1778 -0.2794)
							(mid -0.249642 -0.249642)
							(end -0.2794 -0.1778)
						)
						(arc
							(start -0.2794 0.1778)
							(mid -0.249642 0.249642)
							(end -0.1778 0.2794)
						)
						(arc
							(start 0.1778 0.2794)
							(mid 0.249642 0.249642)
							(end 0.2794 0.1778)
						)
						(arc
							(start 0.2794 -0.1778)
							(mid 0.249642 -0.249642)
							(end 0.1778 -0.2794)
						)
					)
					(width 0)
					(fill yes)
				)
			)
		)
		(pad "2" smd custom
			(at 0 0.4445)
			(size 0.1397 0.1397)
			(layers "F.Cu" "F.Mask" "F.Paste")
			(net "FLA_CS_1")
			(options
				(clearance outline)
				(anchor circle)
			)
			(primitives
				(gr_poly
					(pts
						(arc
							(start -0.1778 -0.2794)
							(mid -0.249642 -0.249642)
							(end -0.2794 -0.1778)
						)
						(arc
							(start -0.2794 0.1778)
							(mid -0.249642 0.249642)
							(end -0.1778 0.2794)
						)
						(arc
							(start 0.1778 0.2794)
							(mid 0.249642 0.249642)
							(end 0.2794 0.1778)
						)
						(arc
							(start 0.2794 -0.1778)
							(mid 0.249642 -0.249642)
							(end 0.1778 -0.2794)
						)
					)
					(width 0)
					(fill yes)
				)
			)
		)
	)
	(footprint ""
		(layer "F.Cu")
		(at 96.882966 -60.325)
		(property "Reference" "STP30"
			(at 0 0 0)
			(layer "F.SilkS")
			(hide yes)
			(effects
				(font
					(size 1.27 1.27)
				)
			)
		)
		(property "Value" "TPAD28"
			(at 0.0127 -1.8034 0)
			(unlocked yes)
			(layer "F.Fab")
			(hide yes)
			(effects
				(font
					(size 1.016 1.016)
					(thickness 0.1524)
				)
			)
		)
		(property "Device Type" "TPAD28"
			(at 0.0127 -3.3274 0)
			(unlocked yes)
			(layer "F.Fab")
			(hide yes)
			(effects
				(font
					(size 1.016 1.016)
					(thickness 0.1524)
				)
			)
		)
		(duplicate_pad_numbers_are_jumpers no)
		(fp_poly
			(pts
				(arc
					(start 0.3556 0)
					(mid -0.3556 0)
					(end 0.3556 0)
				)
			)
			(stroke
				(width 0)
				(type default)
			)
			(fill no)
			(layer "F.CrtYd")
		)
		(fp_poly
			(pts
				(arc
					(start 0.6096 0)
					(mid -0.6096 0)
					(end 0.6096 0)
				)
			)
			(stroke
				(width 0)
				(type default)
			)
			(fill no)
			(layer "F.Fab")
		)
		(pad "1" smd circle
			(at 0 0)
			(size 0.7112 0.7112)
			(layers "F.Cu" "F.Mask" "F.Paste")
			(net "ICE0_TCK")
		)
	)
	(footprint ""
		(layer "F.Cu")
		(at 254.762 -122.555)
		(property "Reference" "R7908"
			(at 0 0 0)
			(layer "F.SilkS")
			(hide yes)
			(effects
				(font
					(size 1.27 1.27)
				)
			)
		)
		(property "Value" "0R2J-2-GP"
			(at 0.064008 -3.993896 0)
			(unlocked yes)
			(layer "F.Fab")
			(hide yes)
			(effects
				(font
					(size 1.016 1.016)
					(thickness 0.1524)
				)
			)
		)
		(property "Device Type" "R402H16"
			(at 0.064008 -5.517896 0)
			(unlocked yes)
			(layer "F.Fab")
			(hide yes)
			(effects
				(font
					(size 1.016 1.016)
					(thickness 0.1524)
				)
			)
		)
		(duplicate_pad_numbers_are_jumpers no)
		(fp_line
			(start -0.508 -0.9398)
			(end -0.508 0.9398)
			(stroke
				(width 0.1524)
				(type default)
			)
			(layer "F.SilkS")
		)
		(fp_line
			(start 0.508 -0.9398)
			(end -0.508 -0.9398)
			(stroke
				(width 0.1524)
				(type default)
			)
			(layer "F.SilkS")
		)
		(fp_rect
			(start -0.508 0.9398)
			(end 0.508 -0.9398)
			(stroke
				(width 0)
				(type default)
			)
			(fill no)
			(layer "F.CrtYd")
		)
		(fp_rect
			(start -0.508 0.9398)
			(end 0.508 -0.9398)
			(stroke
				(width 0)
				(type default)
			)
			(fill no)
			(layer "F.Fab")
		)
		(pad "1" smd custom
			(at 0 -0.4445)
			(size 0.1397 0.1397)
			(layers "F.Cu" "F.Mask" "F.Paste")
			(net "CPU_U192_PIN3_RX")
			(options
				(clearance outline)
				(anchor circle)
			)
			(primitives
				(gr_poly
					(pts
						(arc
							(start -0.1778 -0.2794)
							(mid -0.249642 -0.249642)
							(end -0.2794 -0.1778)
						)
						(arc
							(start -0.2794 0.1778)
							(mid -0.249642 0.249642)
							(end -0.1778 0.2794)
						)
						(arc
							(start 0.1778 0.2794)
							(mid 0.249642 0.249642)
							(end 0.2794 0.1778)
						)
						(arc
							(start 0.2794 -0.1778)
							(mid 0.249642 -0.249642)
							(end 0.1778 -0.2794)
						)
					)
					(width 0)
					(fill yes)
				)
			)
		)
		(pad "2" smd custom
			(at 0 0.4445)
			(size 0.1397 0.1397)
			(layers "F.Cu" "F.Mask" "F.Paste")
			(net "CPU_U192_PIN3_RX_R")
			(options
				(clearance outline)
				(anchor circle)
			)
			(primitives
				(gr_poly
					(pts
						(arc
							(start -0.1778 -0.2794)
							(mid -0.249642 -0.249642)
							(end -0.2794 -0.1778)
						)
						(arc
							(start -0.2794 0.1778)
							(mid -0.249642 0.249642)
							(end -0.1778 0.2794)
						)
						(arc
							(start 0.1778 0.2794)
							(mid 0.249642 0.249642)
							(end 0.2794 0.1778)
						)
						(arc
							(start 0.2794 -0.1778)
							(mid 0.249642 -0.249642)
							(end 0.1778 -0.2794)
						)
					)
					(width 0)
					(fill yes)
				)
			)
		)
	)
	(footprint ""
		(layer "F.Cu")
		(at 318.893952 -56.261 -90)
		(property "Reference" "R210"
			(at 0 0 270)
			(layer "F.SilkS")
			(hide yes)
			(effects
				(font
					(size 1.27 1.27)
				)
			)
		)
		(property "Value" "0R2J-2-GP"
			(at 0.064008 -3.993896 270)
			(unlocked yes)
			(layer "F.Fab")
			(hide yes)
			(effects
				(font
					(size 1.016 1.016)
					(thickness 0.1524)
				)
			)
		)
		(property "Device Type" "R402H16"
			(at 0.064008 -5.517896 270)
			(unlocked yes)
			(layer "F.Fab")
			(hide yes)
			(effects
				(font
					(size 1.016 1.016)
					(thickness 0.1524)
				)
			)
		)
		(duplicate_pad_numbers_are_jumpers no)
		(fp_line
			(start -0.508 -0.9398)
			(end -0.508 0.9398)
			(stroke
				(width 0.1524)
				(type default)
			)
			(layer "F.SilkS")
		)
		(fp_line
			(start 0.508 -0.9398)
			(end -0.508 -0.9398)
			(stroke
				(width 0.1524)
				(type default)
			)
			(layer "F.SilkS")
		)
		(fp_rect
			(start -0.508 0.9398)
			(end 0.508 -0.9398)
			(stroke
				(width 0)
				(type default)
			)
			(fill no)
			(layer "F.CrtYd")
		)
		(fp_rect
			(start -0.508 0.9398)
			(end 0.508 -0.9398)
			(stroke
				(width 0)
				(type default)
			)
			(fill no)
			(layer "F.Fab")
		)
		(pad "1" smd custom
			(at 0 -0.4445 270)
			(size 0.1397 0.1397)
			(layers "F.Cu" "F.Mask" "F.Paste")
			(net "NCSI_10G_RCSDV")
			(options
				(clearance outline)
				(anchor circle)
			)
			(primitives
				(gr_poly
					(pts
						(arc
							(start -0.1778 -0.2794)
							(mid -0.249642 -0.249642)
							(end -0.2794 -0.1778)
						)
						(arc
							(start -0.2794 0.1778)
							(mid -0.249642 0.249642)
							(end -0.1778 0.2794)
						)
						(arc
							(start 0.1778 0.2794)
							(mid 0.249642 0.249642)
							(end 0.2794 0.1778)
						)
						(arc
							(start 0.2794 -0.1778)
							(mid 0.249642 -0.249642)
							(end 0.1778 -0.2794)
						)
					)
					(width 0)
					(fill yes)
				)
			)
		)
		(pad "2" smd custom
			(at 0 0.4445 270)
			(size 0.1397 0.1397)
			(layers "F.Cu" "F.Mask" "F.Paste")
			(net "NCSI_10G_RCSDV_R")
			(options
				(clearance outline)
				(anchor circle)
			)
			(primitives
				(gr_poly
					(pts
						(arc
							(start -0.1778 -0.2794)
							(mid -0.249642 -0.249642)
							(end -0.2794 -0.1778)
						)
						(arc
							(start -0.2794 0.1778)
							(mid -0.249642 0.249642)
							(end -0.1778 0.2794)
						)
						(arc
							(start 0.1778 0.2794)
							(mid 0.249642 0.249642)
							(end 0.2794 0.1778)
						)
						(arc
							(start 0.2794 -0.1778)
							(mid 0.249642 -0.249642)
							(end 0.1778 -0.2794)
						)
					)
					(width 0)
					(fill yes)
				)
			)
		)
	)
)
